(kicad_pcb
	(version 20260206)
	(generator "pcbnew")
	(generator_version "10.0")
	(general
		(thickness 1.6)
		(legacy_teardrops no)
	)
	(paper "A4")
	(title_block
		(title "Bryce Canyon_IOM_IOC_16318-2_OCP.brd")
		(comment 1 "Bryce Canyon / footprints 701-707 of 1605")
	)
	(layers
		(0 "F.Cu" signal "TOP")
		(4 "In1.Cu" signal "L2GND")
		(6 "In2.Cu" signal "L3")
		(8 "In3.Cu" signal "L4VCC")
		(10 "In4.Cu" signal "L5VCC")
		(12 "In5.Cu" signal "L6")
		(14 "In6.Cu" signal "L7GND")
		(2 "B.Cu" signal "BOTTOM")
		(9 "F.Adhes" user "F.Adhesive")
		(11 "B.Adhes" user "B.Adhesive")
		(13 "F.Paste" user "Package Geometry/Pastemask Top")
		(15 "B.Paste" user "Package Geometry/Pastemask Bottom")
		(5 "F.SilkS" user "Ref Des/Silkscreen Top")
		(7 "B.SilkS" user "Ref Des/Silkscreen Bottom")
		(1 "F.Mask" user "Board Geometry/Soldermask Top")
		(3 "B.Mask" user "Board Geometry/Soldermask Bottom")
		(17 "Dwgs.User" user "User.Drawings")
		(19 "Cmts.User" user "User.Comments")
		(21 "Eco1.User" user "User.Eco1")
		(23 "Eco2.User" user "User.Eco2")
		(25 "Edge.Cuts" user "Board Geometry/Outline")
		(27 "Margin" user)
		(31 "F.CrtYd" user "Package Geometry/Place Bound Top")
		(29 "B.CrtYd" user "Package Geometry/Place Bound Bottom")
		(35 "F.Fab" user "Ref Des/Assembly Top")
		(33 "B.Fab" user "Ref Des/Assembly Bottom")
	)
	(footprint ""
		(layer "F.Cu")
		(at 42.2656 -179.451)
		(property "Reference" "R488"
			(at 0 0 0)
			(layer "F.SilkS")
			(hide yes)
			(effects
				(font
					(size 1.27 1.27)
				)
			)
		)
		(property "Value" "2K7R2F-GP"
			(at 0.064008 -3.993896 0)
			(unlocked yes)
			(layer "F.Fab")
			(hide yes)
			(effects
				(font
					(size 1.016 1.016)
					(thickness 0.1524)
				)
			)
		)
		(property "Device Type" "R402H16"
			(at 0.064008 -5.517896 0)
			(unlocked yes)
			(layer "F.Fab")
			(hide yes)
			(effects
				(font
					(size 1.016 1.016)
					(thickness 0.1524)
				)
			)
		)
		(duplicate_pad_numbers_are_jumpers no)
		(fp_line
			(start -0.508 -0.9398)
			(end -0.508 0.9398)
			(stroke
				(width 0.1524)
				(type default)
			)
			(layer "F.SilkS")
		)
		(fp_line
			(start 0.508 -0.9398)
			(end -0.508 -0.9398)
			(stroke
				(width 0.1524)
				(type default)
			)
			(layer "F.SilkS")
		)
		(fp_rect
			(start -0.508 0.9398)
			(end 0.508 -0.9398)
			(stroke
				(width 0)
				(type default)
			)
			(fill no)
			(layer "F.CrtYd")
		)
		(fp_rect
			(start -0.508 0.9398)
			(end 0.508 -0.9398)
			(stroke
				(width 0)
				(type default)
			)
			(fill no)
			(layer "F.Fab")
		)
		(pad "1" smd custom
			(at 0 -0.4445)
			(size 0.1397 0.1397)
			(layers "F.Cu" "F.Mask" "F.Paste")
			(net "P3V3_STBY_LL")
			(options
				(clearance outline)
				(anchor circle)
			)
			(primitives
				(gr_poly
					(pts
						(arc
							(start -0.1778 -0.2794)
							(mid -0.249642 -0.249642)
							(end -0.2794 -0.1778)
						)
						(arc
							(start -0.2794 0.1778)
							(mid -0.249642 0.249642)
							(end -0.1778 0.2794)
						)
						(arc
							(start 0.1778 0.2794)
							(mid 0.249642 0.249642)
							(end 0.2794 0.1778)
						)
						(arc
							(start 0.2794 -0.1778)
							(mid 0.249642 -0.249642)
							(end 0.1778 -0.2794)
						)
					)
					(width 0)
					(fill yes)
				)
			)
		)
		(pad "2" smd custom
			(at 0 0.4445)
			(size 0.1397 0.1397)
			(layers "F.Cu" "F.Mask" "F.Paste")
			(net "P3V3_STBY_LL_R")
			(options
				(clearance outline)
				(anchor circle)
			)
			(primitives
				(gr_poly
					(pts
						(arc
							(start -0.1778 -0.2794)
							(mid -0.249642 -0.249642)
							(end -0.2794 -0.1778)
						)
						(arc
							(start -0.2794 0.1778)
							(mid -0.249642 0.249642)
							(end -0.1778 0.2794)
						)
						(arc
							(start 0.1778 0.2794)
							(mid 0.249642 0.249642)
							(end 0.2794 0.1778)
						)
						(arc
							(start 0.2794 -0.1778)
							(mid 0.249642 -0.249642)
							(end 0.1778 -0.2794)
						)
					)
					(width 0)
					(fill yes)
				)
			)
		)
	)
	(footprint ""
		(layer "F.Cu")
		(at 51.689 -131.7244)
		(property "Reference" "R148"
			(at 0 0 0)
			(layer "F.SilkS")
			(hide yes)
			(effects
				(font
					(size 1.27 1.27)
				)
			)
		)
		(property "Value" "100KR2F-L1-GP"
			(at 0.064008 -3.993896 0)
			(unlocked yes)
			(layer "F.Fab")
			(hide yes)
			(effects
				(font
					(size 1.016 1.016)
					(thickness 0.1524)
				)
			)
		)
		(property "Device Type" "R402H16"
			(at 0.064008 -5.517896 0)
			(unlocked yes)
			(layer "F.Fab")
			(hide yes)
			(effects
				(font
					(size 1.016 1.016)
					(thickness 0.1524)
				)
			)
		)
		(duplicate_pad_numbers_are_jumpers no)
		(fp_line
			(start -0.508 -0.9398)
			(end -0.508 0.9398)
			(stroke
				(width 0.1524)
				(type default)
			)
			(layer "F.SilkS")
		)
		(fp_line
			(start 0.508 -0.9398)
			(end -0.508 -0.9398)
			(stroke
				(width 0.1524)
				(type default)
			)
			(layer "F.SilkS")
		)
		(fp_rect
			(start -0.508 0.9398)
			(end 0.508 -0.9398)
			(stroke
				(width 0)
				(type default)
			)
			(fill no)
			(layer "F.CrtYd")
		)
		(fp_rect
			(start -0.508 0.9398)
			(end 0.508 -0.9398)
			(stroke
				(width 0)
				(type default)
			)
			(fill no)
			(layer "F.Fab")
		)
		(pad "1" smd custom
			(at 0 -0.4445)
			(size 0.1397 0.1397)
			(layers "F.Cu" "F.Mask" "F.Paste")
			(net "IRQ_CPU_SERIAL")
			(options
				(clearance outline)
				(anchor circle)
			)
			(primitives
				(gr_poly
					(pts
						(arc
							(start -0.1778 -0.2794)
							(mid -0.249642 -0.249642)
							(end -0.2794 -0.1778)
						)
						(arc
							(start -0.2794 0.1778)
							(mid -0.249642 0.249642)
							(end -0.1778 0.2794)
						)
						(arc
							(start 0.1778 0.2794)
							(mid 0.249642 0.249642)
							(end 0.2794 0.1778)
						)
						(arc
							(start 0.2794 -0.1778)
							(mid 0.249642 -0.249642)
							(end 0.1778 -0.2794)
						)
					)
					(width 0)
					(fill yes)
				)
			)
		)
		(pad "2" smd custom
			(at 0 0.4445)
			(size 0.1397 0.1397)
			(layers "F.Cu" "F.Mask" "F.Paste")
			(net "GND")
			(options
				(clearance outline)
				(anchor circle)
			)
			(primitives
				(gr_poly
					(pts
						(arc
							(start -0.1778 -0.2794)
							(mid -0.249642 -0.249642)
							(end -0.2794 -0.1778)
						)
						(arc
							(start -0.2794 0.1778)
							(mid -0.249642 0.249642)
							(end -0.1778 0.2794)
						)
						(arc
							(start 0.1778 0.2794)
							(mid 0.249642 0.249642)
							(end 0.2794 0.1778)
						)
						(arc
							(start 0.2794 -0.1778)
							(mid 0.249642 -0.249642)
							(end 0.1778 -0.2794)
						)
					)
					(width 0)
					(fill yes)
				)
			)
		)
	)
	(footprint ""
		(layer "F.Cu")
		(at 128.859788 -6.399022)
		(property "Reference" "R455"
			(at 0 0 0)
			(layer "F.SilkS")
			(hide yes)
			(effects
				(font
					(size 1.27 1.27)
				)
			)
		)
		(property "Value" "1MR3J-L-GP"
			(at -0.0254 -2.5146 0)
			(unlocked yes)
			(layer "F.Fab")
			(hide yes)
			(effects
				(font
					(size 1.016 1.016)
					(thickness 0.1524)
				)
			)
		)
		(property "Device Type" "R603H22"
			(at -0.0254 -4.0386 0)
			(unlocked yes)
			(layer "F.Fab")
			(hide yes)
			(effects
				(font
					(size 1.016 1.016)
					(thickness 0.1524)
				)
			)
		)
		(duplicate_pad_numbers_are_jumpers no)
		(fp_line
			(start -0.4826 0)
			(end -0.2032 0)
			(stroke
				(width 0.2032)
				(type default)
			)
			(layer "F.SilkS")
		)
		(fp_line
			(start 0.2032 0)
			(end 0.4826 0)
			(stroke
				(width 0.2032)
				(type default)
			)
			(layer "F.SilkS")
		)
		(fp_rect
			(start -0.5842 1.3335)
			(end 0.5842 -1.3335)
			(stroke
				(width 0)
				(type default)
			)
			(fill no)
			(layer "F.CrtYd")
		)
		(fp_rect
			(start -0.5842 1.3335)
			(end 0.5842 -1.3335)
			(stroke
				(width 0)
				(type default)
			)
			(fill no)
			(layer "F.Fab")
		)
		(pad "1" smd custom
			(at 0 -0.762)
			(size 0.2159 0.2159)
			(layers "F.Cu" "F.Mask" "F.Paste")
			(net "MB0_CM_GATE_R")
			(options
				(clearance outline)
				(anchor circle)
			)
			(primitives
				(gr_poly
					(pts
						(arc
							(start -0.3302 -0.4318)
							(mid -0.402042 -0.402042)
							(end -0.4318 -0.3302)
						)
						(arc
							(start -0.4318 0.3302)
							(mid -0.402042 0.402042)
							(end -0.3302 0.4318)
						)
						(arc
							(start 0.3302 0.4318)
							(mid 0.402042 0.402042)
							(end 0.4318 0.3302)
						)
						(arc
							(start 0.4318 -0.3302)
							(mid 0.402042 -0.402042)
							(end 0.3302 -0.4318)
						)
					)
					(width 0)
					(fill yes)
				)
			)
		)
		(pad "2" smd custom
			(at 0 0.762)
			(size 0.2159 0.2159)
			(layers "F.Cu" "F.Mask" "F.Paste")
			(net "GND")
			(options
				(clearance outline)
				(anchor circle)
			)
			(primitives
				(gr_poly
					(pts
						(arc
							(start -0.3302 -0.4318)
							(mid -0.402042 -0.402042)
							(end -0.4318 -0.3302)
						)
						(arc
							(start -0.4318 0.3302)
							(mid -0.402042 0.402042)
							(end -0.3302 0.4318)
						)
						(arc
							(start 0.3302 0.4318)
							(mid 0.402042 0.402042)
							(end 0.4318 0.3302)
						)
						(arc
							(start 0.4318 -0.3302)
							(mid 0.402042 -0.402042)
							(end 0.3302 -0.4318)
						)
					)
					(width 0)
					(fill yes)
				)
			)
		)
	)
	(footprint ""
		(layer "F.Cu")
		(at 159.952436 -89.9668)
		(property "Reference" "U43"
			(at 0 0 0)
			(layer "F.SilkS")
			(hide yes)
			(effects
				(font
					(size 1.27 1.27)
				)
			)
		)
		(property "Value" "PCA9306DCTT-GP"
			(at 0 -11.6332 0)
			(unlocked yes)
			(layer "F.Fab")
			(hide yes)
			(effects
				(font
					(size 1.016 1.016)
					(thickness 0.1524)
				)
			)
		)
		(property "Device Type" "SSOIC8H52"
			(at 0 -13.1572 0)
			(unlocked yes)
			(layer "F.Fab")
			(hide yes)
			(effects
				(font
					(size 1.016 1.016)
					(thickness 0.1524)
				)
			)
		)
		(duplicate_pad_numbers_are_jumpers no)
		(fp_line
			(start -1.7018 -0.5842)
			(end -1.7018 2.286)
			(stroke
				(width 0.1524)
				(type default)
			)
			(layer "F.SilkS")
		)
		(fp_line
			(start -1.7018 -0.5842)
			(end 1.0668 -0.5842)
			(stroke
				(width 0.1524)
				(type default)
			)
			(layer "F.SilkS")
		)
		(fp_line
			(start -1.524 0.5842)
			(end -1.524 2.286)
			(stroke
				(width 0.508)
				(type default)
			)
			(layer "F.SilkS")
		)
		(fp_line
			(start -1.397 0)
			(end -1.7018 -0.3048)
			(stroke
				(width 0.1524)
				(type default)
			)
			(layer "F.SilkS")
		)
		(fp_line
			(start -1.397 0)
			(end -1.7018 0.3048)
			(stroke
				(width 0.1524)
				(type default)
			)
			(layer "F.SilkS")
		)
		(fp_line
			(start 1.0668 -0.5842)
			(end 1.0668 0.5842)
			(stroke
				(width 0.1524)
				(type default)
			)
			(layer "F.SilkS")
		)
		(fp_line
			(start 1.0668 0.5842)
			(end -1.524 0.5842)
			(stroke
				(width 0.1524)
				(type default)
			)
			(layer "F.SilkS")
		)
		(fp_poly
			(pts
				(xy -1.1684 -0.5842) (xy 1.0668 -0.5842) (xy 1.0668 0.5842) (xy -1.1684 0.5842)
			)
			(stroke
				(width 0)
				(type default)
			)
			(fill yes)
			(layer "F.SilkS")
		)
		(fp_poly
			(pts
				(xy -1.778 2.54) (xy 1.778 2.54) (xy 1.778 -2.54) (xy -1.778 -2.54)
			)
			(stroke
				(width 0)
				(type default)
			)
			(fill no)
			(layer "F.CrtYd")
		)
		(fp_poly
			(pts
				(xy -1.778 -2.54) (xy 1.778 -2.54) (xy 1.778 2.54) (xy -1.778 2.54)
			)
			(stroke
				(width 0)
				(type default)
			)
			(fill no)
			(layer "F.Fab")
		)
		(pad "1" smd rect
			(at -0.97536 1.6256)
			(size 0.3556 1.524)
			(layers "F.Cu" "F.Mask" "F.Paste")
			(net "GND")
		)
		(pad "2" smd rect
			(at -0.32512 1.6256)
			(size 0.3556 1.524)
			(layers "F.Cu" "F.Mask" "F.Paste")
			(net "P1V8")
		)
		(pad "3" smd rect
			(at 0.32512 1.6256)
			(size 0.3556 1.524)
			(layers "F.Cu" "F.Mask" "F.Paste")
			(net "IOC_SCL_4")
		)
		(pad "4" smd rect
			(at 0.97536 1.6256)
			(size 0.3556 1.524)
			(layers "F.Cu" "F.Mask" "F.Paste")
			(net "IOC_SDA_4")
		)
		(pad "5" smd rect
			(at 0.97536 -1.6256)
			(size 0.3556 1.524)
			(layers "F.Cu" "F.Mask" "F.Paste")
			(net "I2C_IOC_SDA")
		)
		(pad "6" smd rect
			(at 0.32512 -1.6256)
			(size 0.3556 1.524)
			(layers "F.Cu" "F.Mask" "F.Paste")
			(net "I2C_IOC_SCL")
		)
		(pad "7" smd rect
			(at -0.32512 -1.6256)
			(size 0.3556 1.524)
			(layers "F.Cu" "F.Mask" "F.Paste")
			(net "U43_VREF2")
		)
		(pad "8" smd rect
			(at -0.97536 -1.6256)
			(size 0.3556 1.524)
			(layers "F.Cu" "F.Mask" "F.Paste")
			(net "U43_VREF2")
		)
	)
	(footprint ""
		(layer "F.Cu")
		(at 50.673 -131.7498)
		(property "Reference" "R149"
			(at 0 0 0)
			(layer "F.SilkS")
			(hide yes)
			(effects
				(font
					(size 1.27 1.27)
				)
			)
		)
		(property "Value" "100KR2F-L1-GP"
			(at 0.064008 -3.993896 0)
			(unlocked yes)
			(layer "F.Fab")
			(hide yes)
			(effects
				(font
					(size 1.016 1.016)
					(thickness 0.1524)
				)
			)
		)
		(property "Device Type" "R402H16"
			(at 0.064008 -5.517896 0)
			(unlocked yes)
			(layer "F.Fab")
			(hide yes)
			(effects
				(font
					(size 1.016 1.016)
					(thickness 0.1524)
				)
			)
		)
		(duplicate_pad_numbers_are_jumpers no)
		(fp_line
			(start -0.508 -0.9398)
			(end -0.508 0.9398)
			(stroke
				(width 0.1524)
				(type default)
			)
			(layer "F.SilkS")
		)
		(fp_line
			(start 0.508 -0.9398)
			(end -0.508 -0.9398)
			(stroke
				(width 0.1524)
				(type default)
			)
			(layer "F.SilkS")
		)
		(fp_rect
			(start -0.508 0.9398)
			(end 0.508 -0.9398)
			(stroke
				(width 0)
				(type default)
			)
			(fill no)
			(layer "F.CrtYd")
		)
		(fp_rect
			(start -0.508 0.9398)
			(end 0.508 -0.9398)
			(stroke
				(width 0)
				(type default)
			)
			(fill no)
			(layer "F.Fab")
		)
		(pad "1" smd custom
			(at 0 -0.4445)
			(size 0.1397 0.1397)
			(layers "F.Cu" "F.Mask" "F.Paste")
			(net "LPCRST0_N")
			(options
				(clearance outline)
				(anchor circle)
			)
			(primitives
				(gr_poly
					(pts
						(arc
							(start -0.1778 -0.2794)
							(mid -0.249642 -0.249642)
							(end -0.2794 -0.1778)
						)
						(arc
							(start -0.2794 0.1778)
							(mid -0.249642 0.249642)
							(end -0.1778 0.2794)
						)
						(arc
							(start 0.1778 0.2794)
							(mid 0.249642 0.249642)
							(end 0.2794 0.1778)
						)
						(arc
							(start 0.2794 -0.1778)
							(mid 0.249642 -0.249642)
							(end 0.1778 -0.2794)
						)
					)
					(width 0)
					(fill yes)
				)
			)
		)
		(pad "2" smd custom
			(at 0 0.4445)
			(size 0.1397 0.1397)
			(layers "F.Cu" "F.Mask" "F.Paste")
			(net "GND")
			(options
				(clearance outline)
				(anchor circle)
			)
			(primitives
				(gr_poly
					(pts
						(arc
							(start -0.1778 -0.2794)
							(mid -0.249642 -0.249642)
							(end -0.2794 -0.1778)
						)
						(arc
							(start -0.2794 0.1778)
							(mid -0.249642 0.249642)
							(end -0.1778 0.2794)
						)
						(arc
							(start 0.1778 0.2794)
							(mid 0.249642 0.249642)
							(end 0.2794 0.1778)
						)
						(arc
							(start 0.2794 -0.1778)
							(mid 0.249642 -0.249642)
							(end 0.1778 -0.2794)
						)
					)
					(width 0)
					(fill yes)
				)
			)
		)
	)
	(footprint ""
		(layer "F.Cu")
		(at 189.865 -84.201 135)
		(property "Reference" "VIA24"
			(at 0 0 135)
			(layer "F.SilkS")
			(hide yes)
			(effects
				(font
					(size 1.27 1.27)
				)
			)
		)
		(property "Value" "85OHM-8L-1D6MM-L16L18-GP"
			(at 4.064105 0.609655 135)
			(unlocked yes)
			(layer "F.Fab")
			(hide yes)
			(effects
				(font
					(size 1.016 1.016)
					(thickness 0.1524)
				)
			)
		)
		(property "Device Type" "VIA-PCIE-4P-368076"
			(at 4.064105 -0.914474 135)
			(unlocked yes)
			(layer "F.Fab")
			(hide yes)
			(effects
				(font
					(size 1.016 1.016)
					(thickness 0.1524)
				)
			)
		)
		(duplicate_pad_numbers_are_jumpers no)
		(fp_poly
			(pts
				(xy -1.841491 -0.381057) (xy 1.841509 -0.381058) (xy 1.841508 0.380942) (xy -1.841491 0.380942)
			)
			(stroke
				(width 0)
				(type default)
			)
			(fill no)
			(layer "F.CrtYd")
		)
		(fp_poly
			(pts
				(xy -1.841491 -0.381057) (xy 1.841509 -0.381058) (xy 1.841508 0.380942) (xy -1.841491 0.380942)
			)
			(stroke
				(width 0)
				(type default)
			)
			(fill no)
			(layer "F.Fab")
		)
		(pad "1" thru_hole circle
			(at -1.460499 0 135)
			(size 0.508 0.508)
			(drill 0.254)
			(layers "*.Cu" "*.Mask")
			(remove_unused_layers no)
			(net "GND")
			(clearance 0.127)
			(thermal_gap 0.127)
		)
		(pad "2" thru_hole circle
			(at -0.4445 0 135)
			(size 0.508 0.508)
			(drill 0.254)
			(layers "*.Cu" "*.Mask")
			(remove_unused_layers no)
			(net "PCIE_COMP_TO_IOM_15_DP")
			(clearance 0.127)
			(thermal_gap 0.127)
		)
		(pad "3" thru_hole circle
			(at 0.4445 0 135)
			(size 0.508 0.508)
			(drill 0.254)
			(layers "*.Cu" "*.Mask")
			(remove_unused_layers no)
			(net "PCIE_COMP_TO_IOM_15_DN")
			(clearance 0.127)
			(thermal_gap 0.127)
		)
		(pad "4" thru_hole circle
			(at 1.460499 0 135)
			(size 0.508 0.508)
			(drill 0.254)
			(layers "*.Cu" "*.Mask")
			(remove_unused_layers no)
			(net "GND")
			(clearance 0.127)
			(thermal_gap 0.127)
		)
	)
	(footprint ""
		(layer "F.Cu")
		(at 117.6528 -14.5796)
		(property "Reference" "R431"
			(at 0 0 0)
			(layer "F.SilkS")
			(hide yes)
			(effects
				(font
					(size 1.27 1.27)
				)
			)
		)
		(property "Value" "10R2F-L-GP"
			(at 0.064008 -3.993896 0)
			(unlocked yes)
			(layer "F.Fab")
			(hide yes)
			(effects
				(font
					(size 1.016 1.016)
					(thickness 0.1524)
				)
			)
		)
		(property "Device Type" "R402H14"
			(at 0.064008 -5.517896 0)
			(unlocked yes)
			(layer "F.Fab")
			(hide yes)
			(effects
				(font
					(size 1.016 1.016)
					(thickness 0.1524)
				)
			)
		)
		(duplicate_pad_numbers_are_jumpers no)
		(fp_line
			(start -0.508 -0.9398)
			(end -0.508 0.9398)
			(stroke
				(width 0.1524)
				(type default)
			)
			(layer "F.SilkS")
		)
		(fp_line
			(start 0.508 -0.9398)
			(end -0.508 -0.9398)
			(stroke
				(width 0.1524)
				(type default)
			)
			(layer "F.SilkS")
		)
		(fp_rect
			(start -0.508 0.9398)
			(end 0.508 -0.9398)
			(stroke
				(width 0)
				(type default)
			)
			(fill no)
			(layer "F.CrtYd")
		)
		(fp_rect
			(start -0.508 0.9398)
			(end 0.508 -0.9398)
			(stroke
				(width 0)
				(type default)
			)
			(fill no)
			(layer "F.Fab")
		)
		(pad "1" smd custom
			(at 0 -0.4445)
			(size 0.1397 0.1397)
			(layers "F.Cu" "F.Mask" "F.Paste")
			(net "P12V_IOM")
			(options
				(clearance outline)
				(anchor circle)
			)
			(primitives
				(gr_poly
					(pts
						(arc
							(start -0.1778 -0.2794)
							(mid -0.249642 -0.249642)
							(end -0.2794 -0.1778)
						)
						(arc
							(start -0.2794 0.1778)
							(mid -0.249642 0.249642)
							(end -0.1778 0.2794)
						)
						(arc
							(start 0.1778 0.2794)
							(mid 0.249642 0.249642)
							(end 0.2794 0.1778)
						)
						(arc
							(start 0.2794 -0.1778)
							(mid 0.249642 -0.249642)
							(end 0.1778 -0.2794)
						)
					)
					(width 0)
					(fill yes)
				)
			)
		)
		(pad "2" smd custom
			(at 0 0.4445)
			(size 0.1397 0.1397)
			(layers "F.Cu" "F.Mask" "F.Paste")
			(net "MB0_VCC")
			(options
				(clearance outline)
				(anchor circle)
			)
			(primitives
				(gr_poly
					(pts
						(arc
							(start -0.1778 -0.2794)
							(mid -0.249642 -0.249642)
							(end -0.2794 -0.1778)
						)
						(arc
							(start -0.2794 0.1778)
							(mid -0.249642 0.249642)
							(end -0.1778 0.2794)
						)
						(arc
							(start 0.1778 0.2794)
							(mid 0.249642 0.249642)
							(end 0.2794 0.1778)
						)
						(arc
							(start 0.2794 -0.1778)
							(mid 0.249642 -0.249642)
							(end 0.1778 -0.2794)
						)
					)
					(width 0)
					(fill yes)
				)
			)
		)
	)
)
